# T6G (Grand Teton) — schematic netlist excerpt (pin names and nets, part order shuffled) for the footprints in the layout excerpt that follows; sources: Cadence DE-HDL packaged netlist, KiCad conversion of 04192023_DAF0TMB3IC0_F0TG_MB_C_brd_V02_OCP.brd

PC2184  Q_CAP  0.068UF 16V 10% X7R  pkg 0402  page 263 : A = HSC_SS ; B = AGND_HSC
PC334  Q_CAP  0.22UF 16V 10% X7R  pkg 0402  page 215 : A = SW_PVDDCR_SOC_P1_BOOT2_RC ; B = SW_PVDDCR_SOC_P1_PH2

(kicad_pcb
	(version 20260206)
	(generator "pcbnew")
	(generator_version "10.0")
	(general
		(thickness 1.6)
		(legacy_teardrops no)
	)
	(paper "A4")
	(title_block
		(title "04192023_DAF0TMB3IC0_F0TG_MB_C_brd_V02_OCP.brd")
		(comment 1 "Grand Teton / footprints 470-471 of 8354")
	)
	(layers
		(0 "F.Cu" signal "TOP")
		(4 "In1.Cu" signal "GND")
		(6 "In2.Cu" signal "IN1")
		(8 "In3.Cu" signal "GND1")
		(10 "In4.Cu" signal "IN2")
		(12 "In5.Cu" signal "GND2")
		(14 "In6.Cu" signal "IN3")
		(16 "In7.Cu" signal "GND3")
		(18 "In8.Cu" signal "VCC")
		(20 "In9.Cu" signal "VCC1")
		(22 "In10.Cu" signal "GND4")
		(24 "In11.Cu" signal "IN4")
		(26 "In12.Cu" signal "GND5")
		(28 "In13.Cu" signal "IN5")
		(30 "In14.Cu" signal "GND6")
		(32 "In15.Cu" signal "IN6")
		(34 "In16.Cu" signal "GND7")
		(2 "B.Cu" signal "BOTTOM")
		(9 "F.Adhes" user "F.Adhesive")
		(11 "B.Adhes" user "B.Adhesive")
		(13 "F.Paste" user "Package Geometry/Pastemask Top")
		(15 "B.Paste" user "Package Geometry/Pastemask Bottom")
		(5 "F.SilkS" user "Ref Des/Silkscreen Top")
		(7 "B.SilkS" user "Ref Des/Silkscreen Bottom")
		(1 "F.Mask" user "Board Geometry/Soldermask Top")
		(3 "B.Mask" user "Board Geometry/Soldermask Bottom")
		(17 "Dwgs.User" user "User.Drawings")
		(19 "Cmts.User" user "User.Comments")
		(21 "Eco1.User" user "User.Eco1")
		(23 "Eco2.User" user "User.Eco2")
		(25 "Edge.Cuts" user "Board Geometry/Outline")
		(27 "Margin" user)
		(31 "F.CrtYd" user "Package Geometry/Place Bound Top")
		(29 "B.CrtYd" user "Package Geometry/Place Bound Bottom")
		(35 "F.Fab" user "Ref Des/Assembly Top")
		(33 "B.Fab" user "Ref Des/Assembly Bottom")
	)
	(footprint ""
		(layer "F.Cu")
		(at 194.2211 -403.284182 180)
		(property "Reference" "PC2184"
			(at 0 0 180)
			(layer "F.SilkS")
			(hide yes)
			(effects
				(font
					(size 1.27 1.27)
				)
			)
		)
		(property "Value" ""
			(at 0 0 180)
			(layer "F.Fab")
			(effects
				(font
					(size 1.27 1.27)
				)
			)
		)
		(duplicate_pad_numbers_are_jumpers no)
		(fp_line
			(start 0.7874 0.4064)
			(end -0.7874 0.4064)
			(stroke
				(width 0.1524)
				(type default)
			)
			(layer "F.SilkS")
		)
		(fp_line
			(start 0.7874 -0.4064)
			(end 0.7874 0.4064)
			(stroke
				(width 0.1524)
				(type default)
			)
			(layer "F.SilkS")
		)
		(fp_line
			(start -0.7874 0.4064)
			(end -0.7874 -0.4064)
			(stroke
				(width 0.1524)
				(type default)
			)
			(layer "F.SilkS")
		)
		(fp_line
			(start -0.7874 -0.4064)
			(end 0.7874 -0.4064)
			(stroke
				(width 0.1524)
				(type default)
			)
			(layer "F.SilkS")
		)
		(fp_line
			(start 0.67945 0.3048)
			(end 0.120396 0.3048)
			(stroke
				(width 0.1)
				(type default)
			)
			(layer "F.Fab")
		)
		(fp_line
			(start 0.67945 -0.3048)
			(end 0.67945 0.3048)
			(stroke
				(width 0.1)
				(type default)
			)
			(layer "F.Fab")
		)
		(fp_line
			(start 0.12065 -0.2794)
			(end 0.12065 -0.3048)
			(stroke
				(width 0.1)
				(type default)
			)
			(layer "F.Fab")
		)
		(fp_line
			(start 0.12065 -0.3048)
			(end 0.67945 -0.3048)
			(stroke
				(width 0.1)
				(type default)
			)
			(layer "F.Fab")
		)
		(fp_line
			(start 0.120396 0.3048)
			(end 0.120396 0.2794)
			(stroke
				(width 0.1)
				(type default)
			)
			(layer "F.Fab")
		)
		(fp_line
			(start 0.120396 0.2794)
			(end -0.12065 0.2794)
			(stroke
				(width 0.1)
				(type default)
			)
			(layer "F.Fab")
		)
		(fp_line
			(start -0.12065 0.3048)
			(end -0.67945 0.3048)
			(stroke
				(width 0.1)
				(type default)
			)
			(layer "F.Fab")
		)
		(fp_line
			(start -0.12065 0.2794)
			(end -0.12065 0.3048)
			(stroke
				(width 0.1)
				(type default)
			)
			(layer "F.Fab")
		)
		(fp_line
			(start -0.12065 -0.2794)
			(end 0.12065 -0.2794)
			(stroke
				(width 0.1)
				(type default)
			)
			(layer "F.Fab")
		)
		(fp_line
			(start -0.12065 -0.305054)
			(end -0.12065 -0.2794)
			(stroke
				(width 0.1)
				(type default)
			)
			(layer "F.Fab")
		)
		(fp_line
			(start -0.67945 0.3048)
			(end -0.67945 -0.305054)
			(stroke
				(width 0.1)
				(type default)
			)
			(layer "F.Fab")
		)
		(fp_line
			(start -0.67945 -0.305054)
			(end -0.12065 -0.305054)
			(stroke
				(width 0.1)
				(type default)
			)
			(layer "F.Fab")
		)
		(pad "1" smd circle
			(at -0.40005 0 180)
			(size 0 0)
			(layers "F.Cu" "F.Mask" "F.Paste")
			(net "HSC_SS")
		)
		(pad "2" smd circle
			(at 0.40005 0 180)
			(size 0 0)
			(layers "F.Cu" "F.Mask" "F.Paste")
			(net "AGND_HSC")
		)
	)
	(footprint ""
		(layer "F.Cu")
		(at 122.180096 -160.5407 90)
		(property "Reference" "PC334"
			(at 0 0 90)
			(layer "F.SilkS")
			(hide yes)
			(effects
				(font
					(size 1.27 1.27)
				)
			)
		)
		(property "Value" ""
			(at 0 0 90)
			(layer "F.Fab")
			(effects
				(font
					(size 1.27 1.27)
				)
			)
		)
		(duplicate_pad_numbers_are_jumpers no)
		(fp_line
			(start 0.7874 -0.4064)
			(end 0.7874 0.4064)
			(stroke
				(width 0.1524)
				(type default)
			)
			(layer "F.SilkS")
		)
		(fp_line
			(start -0.7874 -0.4064)
			(end 0.7874 -0.4064)
			(stroke
				(width 0.1524)
				(type default)
			)
			(layer "F.SilkS")
		)
		(fp_line
			(start 0.7874 0.4064)
			(end -0.7874 0.4064)
			(stroke
				(width 0.1524)
				(type default)
			)
			(layer "F.SilkS")
		)
		(fp_line
			(start -0.7874 0.4064)
			(end -0.7874 -0.4064)
			(stroke
				(width 0.1524)
				(type default)
			)
			(layer "F.SilkS")
		)
		(fp_line
			(start -0.12065 -0.305054)
			(end -0.12065 -0.2794)
			(stroke
				(width 0.1)
				(type default)
			)
			(layer "F.Fab")
		)
		(fp_line
			(start -0.67945 -0.305054)
			(end -0.12065 -0.305054)
			(stroke
				(width 0.1)
				(type default)
			)
			(layer "F.Fab")
		)
		(fp_line
			(start 0.67945 -0.3048)
			(end 0.67945 0.3048)
			(stroke
				(width 0.1)
				(type default)
			)
			(layer "F.Fab")
		)
		(fp_line
			(start 0.12065 -0.3048)
			(end 0.67945 -0.3048)
			(stroke
				(width 0.1)
				(type default)
			)
			(layer "F.Fab")
		)
		(fp_line
			(start 0.12065 -0.2794)
			(end 0.12065 -0.3048)
			(stroke
				(width 0.1)
				(type default)
			)
			(layer "F.Fab")
		)
		(fp_line
			(start -0.12065 -0.2794)
			(end 0.12065 -0.2794)
			(stroke
				(width 0.1)
				(type default)
			)
			(layer "F.Fab")
		)
		(fp_line
			(start 0.120396 0.2794)
			(end -0.12065 0.2794)
			(stroke
				(width 0.1)
				(type default)
			)
			(layer "F.Fab")
		)
		(fp_line
			(start -0.12065 0.2794)
			(end -0.12065 0.3048)
			(stroke
				(width 0.1)
				(type default)
			)
			(layer "F.Fab")
		)
		(fp_line
			(start 0.67945 0.3048)
			(end 0.120396 0.3048)
			(stroke
				(width 0.1)
				(type default)
			)
			(layer "F.Fab")
		)
		(fp_line
			(start 0.120396 0.3048)
			(end 0.120396 0.2794)
			(stroke
				(width 0.1)
				(type default)
			)
			(layer "F.Fab")
		)
		(fp_line
			(start -0.12065 0.3048)
			(end -0.67945 0.3048)
			(stroke
				(width 0.1)
				(type default)
			)
			(layer "F.Fab")
		)
		(fp_line
			(start -0.67945 0.3048)
			(end -0.67945 -0.305054)
			(stroke
				(width 0.1)
				(type default)
			)
			(layer "F.Fab")
		)
		(pad "1" smd circle
			(at -0.40005 0 90)
			(size 0 0)
			(layers "F.Cu" "F.Mask" "F.Paste")
			(net "SW_PVDDCR_SOC_P1_BOOT2_RC")
		)
		(pad "2" smd circle
			(at 0.40005 0 90)
			(size 0 0)
			(layers "F.Cu" "F.Mask" "F.Paste")
			(net "SW_PVDDCR_SOC_P1_PH2")
		)
	)
)
